# S9S_MB_2U (Grand Teton) — schematic netlist excerpt (pin names and nets, part order shuffled) for the footprints in the layout excerpt that follows; sources: Cadence DE-HDL packaged netlist, KiCad conversion of 03242023_DA0F0TMBIJ0_F0T_Motherboard_J_brd_V01_OCP.brd

PC1649  Q_CAP  100NF 50V 10% X7R  pkg C0402  page 259 : A = P12V_AUX ; B = GND
PC1171  Q_CAP  2.2UF 10V 10% X6S  pkg C0402  page 272 : A = PVCCFA_EHV_FIVRA_CPU0_VDD3 ; B = GND

(kicad_pcb
	(version 20260206)
	(generator "pcbnew")
	(generator_version "10.0")
	(general
		(thickness 1.6)
		(legacy_teardrops no)
	)
	(paper "A4")
	(title_block
		(title "03242023_DA0F0TMBIJ0_F0T_Motherboard_J_brd_V01_OCP.brd")
		(comment 1 "Grand Teton / footprints 1304-1305 of 6105")
	)
	(layers
		(0 "F.Cu" signal "TOP")
		(4 "In1.Cu" signal "GND")
		(6 "In2.Cu" signal "IN1")
		(8 "In3.Cu" signal "GND1")
		(10 "In4.Cu" signal "IN2")
		(12 "In5.Cu" signal "GND2")
		(14 "In6.Cu" signal "IN3")
		(16 "In7.Cu" signal "GND3")
		(18 "In8.Cu" signal "VCC")
		(20 "In9.Cu" signal "VCC1")
		(22 "In10.Cu" signal "GND4")
		(24 "In11.Cu" signal "IN4")
		(26 "In12.Cu" signal "GND5")
		(28 "In13.Cu" signal "IN5")
		(30 "In14.Cu" signal "GND6")
		(32 "In15.Cu" signal "IN6")
		(34 "In16.Cu" signal "GND7")
		(2 "B.Cu" signal "BOTTOM")
		(9 "F.Adhes" user "F.Adhesive")
		(11 "B.Adhes" user "B.Adhesive")
		(13 "F.Paste" user "Package Geometry/Pastemask Top")
		(15 "B.Paste" user "Package Geometry/Pastemask Bottom")
		(5 "F.SilkS" user "Ref Des/Silkscreen Top")
		(7 "B.SilkS" user "Ref Des/Silkscreen Bottom")
		(1 "F.Mask" user "Board Geometry/Soldermask Top")
		(3 "B.Mask" user "Board Geometry/Soldermask Bottom")
		(17 "Dwgs.User" user "User.Drawings")
		(19 "Cmts.User" user "User.Comments")
		(21 "Eco1.User" user "User.Eco1")
		(23 "Eco2.User" user "User.Eco2")
		(25 "Edge.Cuts" user "Board Geometry/Outline")
		(27 "Margin" user)
		(31 "F.CrtYd" user "Package Geometry/Place Bound Top")
		(29 "B.CrtYd" user "Package Geometry/Place Bound Bottom")
		(35 "F.Fab" user "Ref Des/Assembly Top")
		(33 "B.Fab" user "Ref Des/Assembly Bottom")
	)
	(footprint ""
		(layer "F.Cu")
		(at 422.273984 -364.563914 90)
		(property "Reference" "PC1171"
			(at 0 0 90)
			(layer "F.SilkS")
			(hide yes)
			(effects
				(font
					(size 1.27 1.27)
				)
			)
		)
		(property "Value" ""
			(at 0 0 90)
			(layer "F.Fab")
			(effects
				(font
					(size 1.27 1.27)
				)
			)
		)
		(duplicate_pad_numbers_are_jumpers no)
		(fp_line
			(start 0.7874 -0.4064)
			(end 0.7874 0.4064)
			(stroke
				(width 0.1524)
				(type default)
			)
			(layer "F.SilkS")
		)
		(fp_line
			(start -0.7874 -0.4064)
			(end 0.7874 -0.4064)
			(stroke
				(width 0.1524)
				(type default)
			)
			(layer "F.SilkS")
		)
		(fp_line
			(start 0.7874 0.4064)
			(end -0.7874 0.4064)
			(stroke
				(width 0.1524)
				(type default)
			)
			(layer "F.SilkS")
		)
		(fp_line
			(start -0.7874 0.4064)
			(end -0.7874 -0.4064)
			(stroke
				(width 0.1524)
				(type default)
			)
			(layer "F.SilkS")
		)
		(fp_line
			(start -0.12065 -0.305054)
			(end -0.12065 -0.2794)
			(stroke
				(width 0.1)
				(type default)
			)
			(layer "F.Fab")
		)
		(fp_line
			(start -0.67945 -0.305054)
			(end -0.12065 -0.305054)
			(stroke
				(width 0.1)
				(type default)
			)
			(layer "F.Fab")
		)
		(fp_line
			(start 0.67945 -0.3048)
			(end 0.67945 0.3048)
			(stroke
				(width 0.1)
				(type default)
			)
			(layer "F.Fab")
		)
		(fp_line
			(start 0.12065 -0.3048)
			(end 0.67945 -0.3048)
			(stroke
				(width 0.1)
				(type default)
			)
			(layer "F.Fab")
		)
		(fp_line
			(start 0.12065 -0.2794)
			(end 0.12065 -0.3048)
			(stroke
				(width 0.1)
				(type default)
			)
			(layer "F.Fab")
		)
		(fp_line
			(start -0.12065 -0.2794)
			(end 0.12065 -0.2794)
			(stroke
				(width 0.1)
				(type default)
			)
			(layer "F.Fab")
		)
		(fp_line
			(start 0.120396 0.2794)
			(end -0.12065 0.2794)
			(stroke
				(width 0.1)
				(type default)
			)
			(layer "F.Fab")
		)
		(fp_line
			(start -0.12065 0.2794)
			(end -0.12065 0.3048)
			(stroke
				(width 0.1)
				(type default)
			)
			(layer "F.Fab")
		)
		(fp_line
			(start 0.67945 0.3048)
			(end 0.120396 0.3048)
			(stroke
				(width 0.1)
				(type default)
			)
			(layer "F.Fab")
		)
		(fp_line
			(start 0.120396 0.3048)
			(end 0.120396 0.2794)
			(stroke
				(width 0.1)
				(type default)
			)
			(layer "F.Fab")
		)
		(fp_line
			(start -0.12065 0.3048)
			(end -0.67945 0.3048)
			(stroke
				(width 0.1)
				(type default)
			)
			(layer "F.Fab")
		)
		(fp_line
			(start -0.67945 0.3048)
			(end -0.67945 -0.305054)
			(stroke
				(width 0.1)
				(type default)
			)
			(layer "F.Fab")
		)
		(pad "1" smd circle
			(at -0.40005 0 90)
			(size 0 0)
			(layers "F.Cu" "F.Mask" "F.Paste")
			(net "PVCCFA_EHV_FIVRA_CPU0_VDD3")
		)
		(pad "2" smd circle
			(at 0.40005 0 90)
			(size 0 0)
			(layers "F.Cu" "F.Mask" "F.Paste")
			(net "GND")
		)
	)
	(footprint ""
		(layer "F.Cu")
		(at 468.164164 -61.047884 90)
		(property "Reference" "PC1649"
			(at 0 0 90)
			(layer "F.SilkS")
			(hide yes)
			(effects
				(font
					(size 1.27 1.27)
				)
			)
		)
		(property "Value" ""
			(at 0 0 90)
			(layer "F.Fab")
			(effects
				(font
					(size 1.27 1.27)
				)
			)
		)
		(duplicate_pad_numbers_are_jumpers no)
		(fp_line
			(start 0.7874 -0.4064)
			(end 0.7874 0.4064)
			(stroke
				(width 0.1524)
				(type default)
			)
			(layer "F.SilkS")
		)
		(fp_line
			(start -0.7874 -0.4064)
			(end 0.7874 -0.4064)
			(stroke
				(width 0.1524)
				(type default)
			)
			(layer "F.SilkS")
		)
		(fp_line
			(start 0.7874 0.4064)
			(end -0.7874 0.4064)
			(stroke
				(width 0.1524)
				(type default)
			)
			(layer "F.SilkS")
		)
		(fp_line
			(start -0.7874 0.4064)
			(end -0.7874 -0.4064)
			(stroke
				(width 0.1524)
				(type default)
			)
			(layer "F.SilkS")
		)
		(fp_line
			(start -0.12065 -0.305054)
			(end -0.12065 -0.2794)
			(stroke
				(width 0.1)
				(type default)
			)
			(layer "F.Fab")
		)
		(fp_line
			(start -0.67945 -0.305054)
			(end -0.12065 -0.305054)
			(stroke
				(width 0.1)
				(type default)
			)
			(layer "F.Fab")
		)
		(fp_line
			(start 0.67945 -0.3048)
			(end 0.67945 0.3048)
			(stroke
				(width 0.1)
				(type default)
			)
			(layer "F.Fab")
		)
		(fp_line
			(start 0.12065 -0.3048)
			(end 0.67945 -0.3048)
			(stroke
				(width 0.1)
				(type default)
			)
			(layer "F.Fab")
		)
		(fp_line
			(start 0.12065 -0.2794)
			(end 0.12065 -0.3048)
			(stroke
				(width 0.1)
				(type default)
			)
			(layer "F.Fab")
		)
		(fp_line
			(start -0.12065 -0.2794)
			(end 0.12065 -0.2794)
			(stroke
				(width 0.1)
				(type default)
			)
			(layer "F.Fab")
		)
		(fp_line
			(start 0.120396 0.2794)
			(end -0.12065 0.2794)
			(stroke
				(width 0.1)
				(type default)
			)
			(layer "F.Fab")
		)
		(fp_line
			(start -0.12065 0.2794)
			(end -0.12065 0.3048)
			(stroke
				(width 0.1)
				(type default)
			)
			(layer "F.Fab")
		)
		(fp_line
			(start 0.67945 0.3048)
			(end 0.120396 0.3048)
			(stroke
				(width 0.1)
				(type default)
			)
			(layer "F.Fab")
		)
		(fp_line
			(start 0.120396 0.3048)
			(end 0.120396 0.2794)
			(stroke
				(width 0.1)
				(type default)
			)
			(layer "F.Fab")
		)
		(fp_line
			(start -0.12065 0.3048)
			(end -0.67945 0.3048)
			(stroke
				(width 0.1)
				(type default)
			)
			(layer "F.Fab")
		)
		(fp_line
			(start -0.67945 0.3048)
			(end -0.67945 -0.305054)
			(stroke
				(width 0.1)
				(type default)
			)
			(layer "F.Fab")
		)
		(pad "1" smd circle
			(at -0.40005 0 90)
			(size 0 0)
			(layers "F.Cu" "F.Mask" "F.Paste")
			(net "P12V_AUX")
		)
		(pad "2" smd circle
			(at 0.40005 0 90)
			(size 0 0)
			(layers "F.Cu" "F.Mask" "F.Paste")
			(net "GND")
		)
	)
)
